#ISCELL
  pure_quanta quanta_title_block_c *
  *
#ISCELL
  pure_quanta_power universal_gnd *
  page266_i1
#CELL
  pure_quanta tp_tdr_4p_fts *
  page266_i10
#ISCELL
  pure_quanta_power universal_gnd *
  page266_i11
#CELL
  pure_quanta tp_tdr_4p_fts *
  page266_i12
#CELL
  pure_quanta tp_tdr_4p_fts *
  page266_i13
#ISCELL
  pure_quanta_power universal_gnd *
  page266_i14
#CELL
  pure_quanta tp_tdr_4p_fts *
  page266_i15
#CELL
  pure_quanta tp_tdr_4p_fts *
  page266_i16
#CELL
  pure_quanta tp_tdr_4p_fts *
  page266_i17
#ISCELL
  pure_quanta_power universal_gnd *
  page266_i18
#ISCELL
  pure_quanta_power universal_gnd *
  page266_i19
#CELL
  pure_quanta tp_tdr_4p_fts *
  page266_i2
#ISCELL
  pure_quanta_power universal_gnd *
  page266_i20
#ISCELL
  pure_quanta_power universal_gnd *
  page266_i3
#CELL
  pure_quanta tp_tdr_4p_fts *
  page266_i37
#CELL
  pure_quanta tp_tdr_4p_fts *
  page266_i38
#ISCELL
  pure_quanta_power universal_gnd *
  page266_i39
#CELL
  pure_quanta tp_tdr_4p_fts *
  page266_i4
#ISCELL
  pure_quanta_power universal_gnd *
  page266_i40
#ISCELL
  pure_quanta_power universal_gnd *
  page266_i5
#ISCELL
  pure_quanta_power universal_gnd *
  page266_i6
#CELL
  pure_quanta tp_tdr_4p_fts *
  page266_i7
#CELL
  pure_quanta tp_tdr_4p_fts *
  page266_i8
#ISCELL
  pure_quanta_power universal_gnd *
  page266_i9
